(kicad_pcb
	(version 20241229)
	(generator "pcbnew")
	(generator_version "9.0")
	(general
		(thickness 1.63)
		(legacy_teardrops no)
	)
	(paper "A4")
	(title_block
		(title "CM4 Baseboard")
		(date "2026-01-05")
		(rev "1.1.1")
		(company "Antmicro Ltd")
		(comment 1 "www.antmicro.com")
		(comment 9 "footprints 377-380 of 506")
	)
	(layers
		(0 "F.Cu" signal)
		(4 "In1.Cu" power)
		(6 "In2.Cu" power)
		(8 "In3.Cu" signal)
		(10 "In4.Cu" signal)
		(2 "B.Cu" signal)
		(9 "F.Adhes" user "F.Adhesive")
		(11 "B.Adhes" user "B.Adhesive")
		(13 "F.Paste" user)
		(15 "B.Paste" user)
		(5 "F.SilkS" user "F.Silkscreen")
		(7 "B.SilkS" user "B.Silkscreen")
		(1 "F.Mask" user)
		(3 "B.Mask" user)
		(17 "Dwgs.User" user "User.Drawings")
		(19 "Cmts.User" user "User.Comments")
		(21 "Eco1.User" user "User.Eco1")
		(23 "Eco2.User" user "User.Eco2")
		(25 "Edge.Cuts" user)
		(27 "Margin" user)
		(31 "F.CrtYd" user "F.Courtyard")
		(29 "B.CrtYd" user "B.Courtyard")
		(35 "F.Fab" user)
		(33 "B.Fab" user)
	)
	(footprint "antmicro-footprints:SOT-523"
		(layer "B.Cu")
		(at 74.342962 150.6165 90)
		(property "Reference" "Q210"
			(at 1.1665 -1.292962 180)
			(layer "B.SilkS")
			(effects
				(font
					(size 0.7 0.7)
					(thickness 0.15)
				)
				(justify right bottom mirror)
			)
		)
		(property "Value" "PJE138K"
			(at 0.1 -1.824 90)
			(layer "B.Fab")
			(effects
				(font
					(size 0.7 0.7)
					(thickness 0.15)
				)
				(justify right bottom mirror)
			)
		)
		(property "Datasheet" "https://www.mouser.com/datasheet/2/1057/PJE138K-1876698.pdf"
			(at 0 0 90)
			(layer "B.Fab")
			(hide yes)
			(effects
				(font
					(size 1.27 1.27)
					(thickness 0.15)
				)
			)
		)
		(property "MPN" "PJE138K_R1_00001"
			(at 0 0 90)
			(unlocked yes)
			(layer "B.Fab")
			(hide yes)
			(effects
				(font
					(size 1 1)
					(thickness 0.15)
				)
				(justify mirror)
			)
		)
		(property "Manufacturer" "PANJIT"
			(at 0 0 90)
			(unlocked yes)
			(layer "B.Fab")
			(hide yes)
			(effects
				(font
					(size 1 1)
					(thickness 0.15)
				)
				(justify mirror)
			)
		)
		(property "Author" "Antmicro"
			(at 0 0 90)
			(unlocked yes)
			(layer "B.Fab")
			(hide yes)
			(effects
				(font
					(size 1 1)
					(thickness 0.15)
				)
				(justify mirror)
			)
		)
		(property "License" "Apache-2.0"
			(at 0 0 90)
			(unlocked yes)
			(layer "B.Fab")
			(hide yes)
			(effects
				(font
					(size 1 1)
					(thickness 0.15)
				)
				(justify mirror)
			)
		)
		(sheetname "/Compute module/")
		(sheetfile "compute-module.kicad_sch")
		(attr smd)
		(fp_line
			(start -0.927 0.051)
			(end -0.927 0.351)
			(stroke
				(width 0.15)
				(type solid)
			)
			(layer "B.SilkS")
		)
		(fp_line
			(start -0.927 0.351)
			(end -0.725 0.551)
			(stroke
				(width 0.15)
				(type solid)
			)
			(layer "B.SilkS")
		)
		(fp_line
			(start -0.277 0.551)
			(end -0.277 0.75)
			(stroke
				(width 0.15)
				(type solid)
			)
			(layer "B.SilkS")
		)
		(fp_line
			(start -0.725 0.551)
			(end -0.277 0.551)
			(stroke
				(width 0.15)
				(type solid)
			)
			(layer "B.SilkS")
		)
		(fp_circle
			(center -0.9652 -0.9652)
			(end -0.9152 -0.9652)
			(stroke
				(width 0.15)
				(type solid)
			)
			(fill yes)
			(layer "B.SilkS")
		)
		(fp_line
			(start -1.12 -1.15)
			(end 1.1 -1.15)
			(stroke
				(width 0.05)
				(type solid)
			)
			(layer "B.CrtYd")
		)
		(fp_line
			(start 1.1 1.16)
			(end 1.1 -1.15)
			(stroke
				(width 0.05)
				(type solid)
			)
			(layer "B.CrtYd")
		)
		(fp_line
			(start -1.12 1.16)
			(end -1.12 -1.15)
			(stroke
				(width 0.05)
				(type solid)
			)
			(layer "B.CrtYd")
		)
		(fp_line
			(start -1.12 1.16)
			(end 1.1 1.16)
			(stroke
				(width 0.05)
				(type solid)
			)
			(layer "B.CrtYd")
		)
		(fp_line
			(start 0.8 -0.424)
			(end -0.802 -0.424)
			(stroke
				(width 0.15)
				(type solid)
			)
			(layer "B.Fab")
		)
		(fp_line
			(start -0.802 0.276)
			(end -0.802 -0.424)
			(stroke
				(width 0.15)
				(type solid)
			)
			(layer "B.Fab")
		)
		(fp_line
			(start 0.8 0.425)
			(end 0.8 -0.424)
			(stroke
				(width 0.15)
				(type solid)
			)
			(layer "B.Fab")
		)
		(fp_line
			(start 0.8 0.425)
			(end -0.652 0.425)
			(stroke
				(width 0.15)
				(type solid)
			)
			(layer "B.Fab")
		)
		(fp_line
			(start -0.652 0.425)
			(end -0.802 0.276)
			(stroke
				(width 0.15)
				(type solid)
			)
			(layer "B.Fab")
		)
		(fp_circle
			(center -0.9652 -0.9652)
			(end -0.9144 -0.9652)
			(stroke
				(width 0.15)
				(type solid)
			)
			(fill no)
			(layer "B.Fab")
		)
		(fp_text user "${REFERENCE}"
			(at -1.12 -3.824 270)
			(layer "B.Fab")
			(effects
				(font
					(size 0.7 0.7)
					(thickness 0.15)
				)
				(justify left bottom mirror)
			)
		)
		(fp_text user "License: Apache-2.0"
			(at -1.12 -5.024 270)
			(layer "B.Fab")
			(effects
				(font
					(size 0.7 0.7)
					(thickness 0.15)
				)
				(justify left bottom mirror)
			)
		)
		(fp_text user "Author: Antmicro"
			(at -1.12 -6.224 270)
			(layer "B.Fab")
			(effects
				(font
					(size 0.7 0.7)
					(thickness 0.15)
				)
				(justify left bottom mirror)
			)
		)
		(pad "1" smd rect
			(at -0.5 -0.65 90)
			(size 0.4 0.51)
			(layers "B.Cu" "B.Mask" "B.Paste")
			(net 22 "+1V8")
			(pinfunction "G")
			(pintype "input")
		)
		(pad "2" smd rect
			(at 0.498 -0.65 90)
			(size 0.4 0.51)
			(layers "B.Cu" "B.Mask" "B.Paste")
			(net 3 "GND")
			(pinfunction "S")
			(pintype "passive")
		)
		(pad "3" smd rect
			(at 0 0.652 90)
			(size 0.4 0.51)
			(layers "B.Cu" "B.Mask" "B.Paste")
			(net 331 "Net-(Q210-D)")
			(pinfunction "D")
			(pintype "passive")
		)
	)
	(footprint "antmicro-footprints:C_0805_2012Metric"
		(layer "B.Cu")
		(at 56.667962 158.2365 90)
		(descr "Capacitor SMD 0805")
		(tags "capacitor SMD 0805")
		(property "Reference" "C312"
			(at 1.575 1.03 90)
			(layer "B.SilkS")
			(effects
				(font
					(size 0.7 0.7)
					(thickness 0.15)
				)
				(justify right bottom mirror)
			)
		)
		(property "Value" "C_22u_25V_0805"
			(at -2.055717 -1.963152 90)
			(layer "B.Fab")
			(effects
				(font
					(size 0.7 0.7)
					(thickness 0.15)
				)
				(justify right bottom mirror)
			)
		)
		(property "Datasheet" "https://product.samsungsem.com/mlcc/CL21A226MAYNNN.do"
			(at 0 0 90)
			(layer "B.Fab")
			(hide yes)
			(effects
				(font
					(size 1.27 1.27)
					(thickness 0.15)
				)
			)
		)
		(property "Manufacturer" "Samsung Electro-Mechanics"
			(at 0 0 90)
			(unlocked yes)
			(layer "B.Fab")
			(hide yes)
			(effects
				(font
					(size 1 1)
					(thickness 0.15)
				)
				(justify mirror)
			)
		)
		(property "MPN" "CL21A226MAYNNNE"
			(at 0 0 90)
			(unlocked yes)
			(layer "B.Fab")
			(hide yes)
			(effects
				(font
					(size 1 1)
					(thickness 0.15)
				)
				(justify mirror)
			)
		)
		(property "Val" "22u"
			(at 0 0 90)
			(unlocked yes)
			(layer "B.Fab")
			(hide yes)
			(effects
				(font
					(size 1 1)
					(thickness 0.15)
				)
				(justify mirror)
			)
		)
		(property "License" "Apache-2.0"
			(at 0 0 90)
			(unlocked yes)
			(layer "B.Fab")
			(hide yes)
			(effects
				(font
					(size 1 1)
					(thickness 0.15)
				)
				(justify mirror)
			)
		)
		(property "Author" "Antmicro"
			(at 0 0 90)
			(unlocked yes)
			(layer "B.Fab")
			(hide yes)
			(effects
				(font
					(size 1 1)
					(thickness 0.15)
				)
				(justify mirror)
			)
		)
		(property "Voltage" "25V"
			(at 0 0 90)
			(unlocked yes)
			(layer "B.Fab")
			(hide yes)
			(effects
				(font
					(size 1 1)
					(thickness 0.15)
				)
				(justify mirror)
			)
		)
		(property "Dielectric" "X5R"
			(at 0 0 90)
			(unlocked yes)
			(layer "B.Fab")
			(hide yes)
			(effects
				(font
					(size 1 1)
					(thickness 0.15)
				)
				(justify mirror)
			)
		)
		(property "Public" "False"
			(at 0 0 90)
			(unlocked yes)
			(layer "B.Fab")
			(hide yes)
			(effects
				(font
					(size 1 1)
					(thickness 0.15)
				)
				(justify mirror)
			)
		)
		(sheetname "/Supply/")
		(sheetfile "supply.kicad_sch")
		(attr smd)
		(fp_line
			(start -0.3 -0.7)
			(end 0.3 -0.7)
			(stroke
				(width 0.15)
				(type solid)
			)
			(layer "B.SilkS")
		)
		(fp_line
			(start -0.3 0.7)
			(end 0.3 0.7)
			(stroke
				(width 0.15)
				(type solid)
			)
			(layer "B.SilkS")
		)
		(fp_rect
			(start 1.95 0.9)
			(end -1.95 -0.9)
			(stroke
				(width 0.05)
				(type default)
			)
			(fill no)
			(layer "B.CrtYd")
		)
		(fp_rect
			(start -0.95 0.675)
			(end 0.95 -0.675)
			(stroke
				(width 0.15)
				(type solid)
			)
			(fill no)
			(layer "B.Fab")
		)
		(fp_text user "Author: Antmicro"
			(at -1.9 -5.947 270)
			(layer "B.Fab")
			(effects
				(font
					(size 0.7 0.7)
					(thickness 0.15)
				)
				(justify left bottom mirror)
			)
		)
		(fp_text user "${REFERENCE}"
			(at -1.9 -3.947 270)
			(layer "B.Fab")
			(effects
				(font
					(size 0.7 0.7)
					(thickness 0.15)
				)
				(justify left bottom mirror)
			)
		)
		(fp_text user "License: Apache-2.0"
			(at -1.9 -4.947 270)
			(layer "B.Fab")
			(effects
				(font
					(size 0.7 0.7)
					(thickness 0.15)
				)
				(justify left bottom mirror)
			)
		)
		(pad "1" smd roundrect
			(at -1.1 0 90)
			(size 1.2 1.3)
			(layers "B.Cu" "B.Mask" "B.Paste")
			(roundrect_rratio 0.25)
			(net 77 "/Supply/OUT_5V")
			(pintype "passive")
		)
		(pad "2" smd roundrect
			(at 1.1 0 90)
			(size 1.2 1.3)
			(layers "B.Cu" "B.Mask" "B.Paste")
			(roundrect_rratio 0.25)
			(net 3 "GND")
			(pintype "passive")
		)
	)
	(footprint "antmicro-footprints:R_0402_1005Metric"
		(layer "B.Cu")
		(at 52.517962 161.8145 180)
		(descr "Resistor SMD 0402")
		(tags "resistor SMD 0402")
		(property "Reference" "R306"
			(at -1.37 0.468 0)
			(layer "B.SilkS")
			(effects
				(font
					(size 0.7 0.7)
					(thickness 0.15)
				)
				(justify left bottom mirror)
			)
		)
		(property "Value" "R_470k_0402"
			(at -1.011843 -1.772047 0)
			(layer "B.Fab")
			(effects
				(font
					(size 0.7 0.7)
					(thickness 0.15)
				)
				(justify left bottom mirror)
			)
		)
		(property "Datasheet" "https://www.bourns.com/docs/product-datasheets/cr.pdf"
			(at 0 0 180)
			(layer "B.Fab")
			(hide yes)
			(effects
				(font
					(size 1.27 1.27)
					(thickness 0.15)
				)
			)
		)
		(property "MPN" "CR0402-FX-4703GLF"
			(at 0 0 180)
			(unlocked yes)
			(layer "B.Fab")
			(hide yes)
			(effects
				(font
					(size 1 1)
					(thickness 0.15)
				)
				(justify mirror)
			)
		)
		(property "Manufacturer" "Bourns"
			(at 0 0 180)
			(unlocked yes)
			(layer "B.Fab")
			(hide yes)
			(effects
				(font
					(size 1 1)
					(thickness 0.15)
				)
				(justify mirror)
			)
		)
		(property "License" "Apache-2.0"
			(at 0 0 180)
			(unlocked yes)
			(layer "B.Fab")
			(hide yes)
			(effects
				(font
					(size 1 1)
					(thickness 0.15)
				)
				(justify mirror)
			)
		)
		(property "Author" "Antmicro"
			(at 0 0 180)
			(unlocked yes)
			(layer "B.Fab")
			(hide yes)
			(effects
				(font
					(size 1 1)
					(thickness 0.15)
				)
				(justify mirror)
			)
		)
		(property "Val" "470k"
			(at 0 0 180)
			(unlocked yes)
			(layer "B.Fab")
			(hide yes)
			(effects
				(font
					(size 1 1)
					(thickness 0.15)
				)
				(justify mirror)
			)
		)
		(property "Tolerance" "1%"
			(at 0 0 180)
			(unlocked yes)
			(layer "B.Fab")
			(hide yes)
			(effects
				(font
					(size 1 1)
					(thickness 0.15)
				)
				(justify mirror)
			)
		)
		(sheetname "/Supply/")
		(sheetfile "supply.kicad_sch")
		(attr smd)
		(fp_rect
			(start -0.925 0.47)
			(end 0.925 -0.47)
			(stroke
				(width 0.05)
				(type default)
			)
			(fill no)
			(layer "B.CrtYd")
		)
		(fp_rect
			(start -0.5 0.25)
			(end 0.5 -0.25)
			(stroke
				(width 0.15)
				(type solid)
			)
			(fill no)
			(layer "B.Fab")
		)
		(fp_text user "Author: Antmicro"
			(at -0.95 -4.169 0)
			(layer "B.Fab")
			(effects
				(font
					(size 0.7 0.7)
					(thickness 0.15)
				)
				(justify left bottom mirror)
			)
		)
		(fp_text user "License: Apache-2.0"
			(at -0.95 -5.169 0)
			(layer "B.Fab")
			(effects
				(font
					(size 0.7 0.7)
					(thickness 0.15)
				)
				(justify left bottom mirror)
			)
		)
		(fp_text user "${REFERENCE}"
			(at -0.95 -3.168 0)
			(layer "B.Fab")
			(effects
				(font
					(size 0.7 0.7)
					(thickness 0.15)
				)
				(justify left bottom mirror)
			)
		)
		(pad "1" smd roundrect
			(at -0.48 0 180)
			(size 0.59 0.64)
			(layers "B.Cu" "B.Mask" "B.Paste")
			(roundrect_rratio 0.25)
			(net 3 "GND")
			(pintype "passive")
		)
		(pad "2" smd roundrect
			(at 0.48 0 180)
			(size 0.59 0.64)
			(layers "B.Cu" "B.Mask" "B.Paste")
			(roundrect_rratio 0.25)
			(net 337 "Net-(Q303-BIAS)")
			(pintype "passive")
		)
	)
	(footprint "antmicro-footprints:R_0402_1005Metric"
		(layer "B.Cu")
		(at 71.927962 128.9565)
		(descr "Resistor SMD 0402")
		(tags "resistor SMD 0402")
		(property "Reference" "R413"
			(at -0.88 2.37 0)
			(layer "B.SilkS")
			(effects
				(font
					(size 0.7 0.7)
					(thickness 0.15)
				)
				(justify right bottom mirror)
			)
		)
		(property "Value" "R_200R_0402"
			(at -1.011843 -1.772047 0)
			(layer "B.Fab")
			(effects
				(font
					(size 0.7 0.7)
					(thickness 0.15)
				)
				(justify right bottom mirror)
			)
		)
		(property "Datasheet" "https://www.bourns.com/docs/product-datasheets/cr.pdf"
			(at 0 0 0)
			(layer "B.Fab")
			(hide yes)
			(effects
				(font
					(size 1.27 1.27)
					(thickness 0.15)
				)
			)
		)
		(property "Manufacturer" "Bourns"
			(at 0 0 0)
			(unlocked yes)
			(layer "B.Fab")
			(hide yes)
			(effects
				(font
					(size 1 1)
					(thickness 0.15)
				)
				(justify mirror)
			)
		)
		(property "MPN" "CR0402-FX-2000GLF"
			(at 0 0 0)
			(unlocked yes)
			(layer "B.Fab")
			(hide yes)
			(effects
				(font
					(size 1 1)
					(thickness 0.15)
				)
				(justify mirror)
			)
		)
		(property "Val" "200R"
			(at 0 0 0)
			(unlocked yes)
			(layer "B.Fab")
			(hide yes)
			(effects
				(font
					(size 1 1)
					(thickness 0.15)
				)
				(justify mirror)
			)
		)
		(property "License" "Apache-2.0"
			(at 0 0 0)
			(unlocked yes)
			(layer "B.Fab")
			(hide yes)
			(effects
				(font
					(size 1 1)
					(thickness 0.15)
				)
				(justify mirror)
			)
		)
		(property "Author" "Antmicro"
			(at 0 0 0)
			(unlocked yes)
			(layer "B.Fab")
			(hide yes)
			(effects
				(font
					(size 1 1)
					(thickness 0.15)
				)
				(justify mirror)
			)
		)
		(property "Tolerance" "1%"
			(at 0 0 0)
			(unlocked yes)
			(layer "B.Fab")
			(hide yes)
			(effects
				(font
					(size 1 1)
					(thickness 0.15)
				)
				(justify mirror)
			)
		)
		(sheetname "/Ethernet/")
		(sheetfile "ethernet.kicad_sch")
		(attr smd)
		(fp_rect
			(start -0.925 0.47)
			(end 0.925 -0.47)
			(stroke
				(width 0.05)
				(type default)
			)
			(fill no)
			(layer "B.CrtYd")
		)
		(fp_rect
			(start -0.5 0.25)
			(end 0.5 -0.25)
			(stroke
				(width 0.15)
				(type solid)
			)
			(fill no)
			(layer "B.Fab")
		)
		(fp_text user "License: Apache-2.0"
			(at -0.95 -5.169 180)
			(layer "B.Fab")
			(effects
				(font
					(size 0.7 0.7)
					(thickness 0.15)
				)
				(justify left bottom mirror)
			)
		)
		(fp_text user "Author: Antmicro"
			(at -0.95 -4.169 180)
			(layer "B.Fab")
			(effects
				(font
					(size 0.7 0.7)
					(thickness 0.15)
				)
				(justify left bottom mirror)
			)
		)
		(fp_text user "${REFERENCE}"
			(at -0.95 -3.168 180)
			(layer "B.Fab")
			(effects
				(font
					(size 0.7 0.7)
					(thickness 0.15)
				)
				(justify left bottom mirror)
			)
		)
		(pad "1" smd roundrect
			(at -0.48 0)
			(size 0.59 0.64)
			(layers "B.Cu" "B.Mask" "B.Paste")
			(roundrect_rratio 0.25)
			(net 3 "GND")
			(pintype "passive")
		)
		(pad "2" smd roundrect
			(at 0.48 0)
			(size 0.59 0.64)
			(layers "B.Cu" "B.Mask" "B.Paste")
			(roundrect_rratio 0.25)
			(net 92 "Net-(C403-Pad1)")
			(pintype "passive")
		)
	)
)
